(kicad_pcb
	(version 20260206)
	(generator "pcbnew")
	(generator_version "10.0")
	(general
		(thickness 1.6)
		(legacy_teardrops no)
	)
	(paper "A4")
	(title_block
		(title "04192023_DAF0TMB3IC0_F0TG_MB_C_brd_V02_OCP.brd")
		(comment 1 "Grand Teton / footprints 3286-3292 of 8354")
	)
	(layers
		(0 "F.Cu" signal "TOP")
		(4 "In1.Cu" signal "GND")
		(6 "In2.Cu" signal "IN1")
		(8 "In3.Cu" signal "GND1")
		(10 "In4.Cu" signal "IN2")
		(12 "In5.Cu" signal "GND2")
		(14 "In6.Cu" signal "IN3")
		(16 "In7.Cu" signal "GND3")
		(18 "In8.Cu" signal "VCC")
		(20 "In9.Cu" signal "VCC1")
		(22 "In10.Cu" signal "GND4")
		(24 "In11.Cu" signal "IN4")
		(26 "In12.Cu" signal "GND5")
		(28 "In13.Cu" signal "IN5")
		(30 "In14.Cu" signal "GND6")
		(32 "In15.Cu" signal "IN6")
		(34 "In16.Cu" signal "GND7")
		(2 "B.Cu" signal "BOTTOM")
		(9 "F.Adhes" user "F.Adhesive")
		(11 "B.Adhes" user "B.Adhesive")
		(13 "F.Paste" user "Package Geometry/Pastemask Top")
		(15 "B.Paste" user "Package Geometry/Pastemask Bottom")
		(5 "F.SilkS" user "Ref Des/Silkscreen Top")
		(7 "B.SilkS" user "Ref Des/Silkscreen Bottom")
		(1 "F.Mask" user "Board Geometry/Soldermask Top")
		(3 "B.Mask" user "Board Geometry/Soldermask Bottom")
		(17 "Dwgs.User" user "User.Drawings")
		(19 "Cmts.User" user "User.Comments")
		(21 "Eco1.User" user "User.Eco1")
		(23 "Eco2.User" user "User.Eco2")
		(25 "Edge.Cuts" user "Board Geometry/Outline")
		(27 "Margin" user)
		(31 "F.CrtYd" user "Package Geometry/Place Bound Top")
		(29 "B.CrtYd" user "Package Geometry/Place Bound Bottom")
		(35 "F.Fab" user "Ref Des/Assembly Top")
		(33 "B.Fab" user "Ref Des/Assembly Bottom")
	)
	(footprint ""
		(layer "F.Cu")
		(at 453.719946 -102.598728)
		(property "Reference" "R1908"
			(at 0 0 0)
			(layer "F.SilkS")
			(hide yes)
			(effects
				(font
					(size 1.27 1.27)
				)
			)
		)
		(property "Value" ""
			(at 0 0 0)
			(layer "F.Fab")
			(effects
				(font
					(size 1.27 1.27)
				)
			)
		)
		(duplicate_pad_numbers_are_jumpers no)
		(fp_line
			(start -0.7874 -0.4064)
			(end 0.7874 -0.4064)
			(stroke
				(width 0.1524)
				(type default)
			)
			(layer "F.SilkS")
		)
		(fp_line
			(start -0.7874 0.4064)
			(end -0.7874 -0.4064)
			(stroke
				(width 0.1524)
				(type default)
			)
			(layer "F.SilkS")
		)
		(fp_line
			(start 0.7874 -0.4064)
			(end 0.7874 0.4064)
			(stroke
				(width 0.1524)
				(type default)
			)
			(layer "F.SilkS")
		)
		(fp_line
			(start 0.7874 0.4064)
			(end -0.7874 0.4064)
			(stroke
				(width 0.1524)
				(type default)
			)
			(layer "F.SilkS")
		)
		(fp_line
			(start -0.67945 -0.305054)
			(end -0.12065 -0.305054)
			(stroke
				(width 0.1)
				(type default)
			)
			(layer "F.Fab")
		)
		(fp_line
			(start -0.67945 0.3048)
			(end -0.67945 -0.305054)
			(stroke
				(width 0.1)
				(type default)
			)
			(layer "F.Fab")
		)
		(fp_line
			(start -0.12065 -0.305054)
			(end -0.12065 -0.2794)
			(stroke
				(width 0.1)
				(type default)
			)
			(layer "F.Fab")
		)
		(fp_line
			(start -0.12065 -0.2794)
			(end 0.12065 -0.2794)
			(stroke
				(width 0.1)
				(type default)
			)
			(layer "F.Fab")
		)
		(fp_line
			(start -0.12065 0.2794)
			(end -0.12065 0.3048)
			(stroke
				(width 0.1)
				(type default)
			)
			(layer "F.Fab")
		)
		(fp_line
			(start -0.12065 0.3048)
			(end -0.67945 0.3048)
			(stroke
				(width 0.1)
				(type default)
			)
			(layer "F.Fab")
		)
		(fp_line
			(start 0.120396 0.2794)
			(end -0.12065 0.2794)
			(stroke
				(width 0.1)
				(type default)
			)
			(layer "F.Fab")
		)
		(fp_line
			(start 0.120396 0.3048)
			(end 0.120396 0.2794)
			(stroke
				(width 0.1)
				(type default)
			)
			(layer "F.Fab")
		)
		(fp_line
			(start 0.12065 -0.3048)
			(end 0.67945 -0.3048)
			(stroke
				(width 0.1)
				(type default)
			)
			(layer "F.Fab")
		)
		(fp_line
			(start 0.12065 -0.2794)
			(end 0.12065 -0.3048)
			(stroke
				(width 0.1)
				(type default)
			)
			(layer "F.Fab")
		)
		(fp_line
			(start 0.67945 -0.3048)
			(end 0.67945 0.3048)
			(stroke
				(width 0.1)
				(type default)
			)
			(layer "F.Fab")
		)
		(fp_line
			(start 0.67945 0.3048)
			(end 0.120396 0.3048)
			(stroke
				(width 0.1)
				(type default)
			)
			(layer "F.Fab")
		)
		(pad "1" smd circle
			(at -0.40005 0)
			(size 0 0)
			(layers "F.Cu" "F.Mask" "F.Paste")
			(net "P3V3_AUX")
		)
		(pad "2" smd circle
			(at 0.40005 0)
			(size 0 0)
			(layers "F.Cu" "F.Mask" "F.Paste")
			(net "OCP_SFF_PRSNT3_R_N")
		)
	)
	(footprint ""
		(layer "F.Cu")
		(at 345.176094 -339.676232 -90)
		(property "Reference" "PC137"
			(at 0 0 270)
			(layer "F.SilkS")
			(hide yes)
			(effects
				(font
					(size 1.27 1.27)
				)
			)
		)
		(property "Value" ""
			(at 0 0 270)
			(layer "F.Fab")
			(effects
				(font
					(size 1.27 1.27)
				)
			)
		)
		(duplicate_pad_numbers_are_jumpers no)
		(fp_line
			(start -0.7874 0.4064)
			(end -0.7874 -0.4064)
			(stroke
				(width 0.1524)
				(type default)
			)
			(layer "F.SilkS")
		)
		(fp_line
			(start 0.7874 0.4064)
			(end -0.7874 0.4064)
			(stroke
				(width 0.1524)
				(type default)
			)
			(layer "F.SilkS")
		)
		(fp_line
			(start -0.7874 -0.4064)
			(end 0.7874 -0.4064)
			(stroke
				(width 0.1524)
				(type default)
			)
			(layer "F.SilkS")
		)
		(fp_line
			(start 0.7874 -0.4064)
			(end 0.7874 0.4064)
			(stroke
				(width 0.1524)
				(type default)
			)
			(layer "F.SilkS")
		)
		(fp_line
			(start -0.67945 0.3048)
			(end -0.67945 -0.305054)
			(stroke
				(width 0.1)
				(type default)
			)
			(layer "F.Fab")
		)
		(fp_line
			(start -0.12065 0.3048)
			(end -0.67945 0.3048)
			(stroke
				(width 0.1)
				(type default)
			)
			(layer "F.Fab")
		)
		(fp_line
			(start 0.120396 0.3048)
			(end 0.120396 0.2794)
			(stroke
				(width 0.1)
				(type default)
			)
			(layer "F.Fab")
		)
		(fp_line
			(start 0.67945 0.3048)
			(end 0.120396 0.3048)
			(stroke
				(width 0.1)
				(type default)
			)
			(layer "F.Fab")
		)
		(fp_line
			(start -0.12065 0.2794)
			(end -0.12065 0.3048)
			(stroke
				(width 0.1)
				(type default)
			)
			(layer "F.Fab")
		)
		(fp_line
			(start 0.120396 0.2794)
			(end -0.12065 0.2794)
			(stroke
				(width 0.1)
				(type default)
			)
			(layer "F.Fab")
		)
		(fp_line
			(start -0.12065 -0.2794)
			(end 0.12065 -0.2794)
			(stroke
				(width 0.1)
				(type default)
			)
			(layer "F.Fab")
		)
		(fp_line
			(start 0.12065 -0.2794)
			(end 0.12065 -0.3048)
			(stroke
				(width 0.1)
				(type default)
			)
			(layer "F.Fab")
		)
		(fp_line
			(start 0.12065 -0.3048)
			(end 0.67945 -0.3048)
			(stroke
				(width 0.1)
				(type default)
			)
			(layer "F.Fab")
		)
		(fp_line
			(start 0.67945 -0.3048)
			(end 0.67945 0.3048)
			(stroke
				(width 0.1)
				(type default)
			)
			(layer "F.Fab")
		)
		(fp_line
			(start -0.67945 -0.305054)
			(end -0.12065 -0.305054)
			(stroke
				(width 0.1)
				(type default)
			)
			(layer "F.Fab")
		)
		(fp_line
			(start -0.12065 -0.305054)
			(end -0.12065 -0.2794)
			(stroke
				(width 0.1)
				(type default)
			)
			(layer "F.Fab")
		)
		(pad "1" smd circle
			(at -0.40005 0 270)
			(size 0 0)
			(layers "F.Cu" "F.Mask" "F.Paste")
			(net "SW_PVDDCR_CPU1_P0_BOOT5_R")
		)
		(pad "2" smd circle
			(at 0.40005 0 270)
			(size 0 0)
			(layers "F.Cu" "F.Mask" "F.Paste")
			(net "SW_PVDDCR_CPU1_P0_BOOTR5")
		)
	)
	(footprint ""
		(layer "F.Cu")
		(at 251.009912 -54.440582 90)
		(property "Reference" "PC2205"
			(at 0 0 90)
			(layer "F.SilkS")
			(hide yes)
			(effects
				(font
					(size 1.27 1.27)
				)
			)
		)
		(property "Value" ""
			(at 0 0 90)
			(layer "F.Fab")
			(effects
				(font
					(size 1.27 1.27)
				)
			)
		)
		(duplicate_pad_numbers_are_jumpers no)
		(fp_line
			(start 1.2954 -0.5842)
			(end 1.2954 0.5842)
			(stroke
				(width 0.1524)
				(type default)
			)
			(layer "F.SilkS")
		)
		(fp_line
			(start -1.2954 -0.5842)
			(end 1.2954 -0.5842)
			(stroke
				(width 0.1524)
				(type default)
			)
			(layer "F.SilkS")
		)
		(fp_line
			(start 1.2954 0.5842)
			(end -1.2954 0.5842)
			(stroke
				(width 0.1524)
				(type default)
			)
			(layer "F.SilkS")
		)
		(fp_line
			(start -1.2954 0.5842)
			(end -1.2954 -0.5842)
			(stroke
				(width 0.1524)
				(type default)
			)
			(layer "F.SilkS")
		)
		(fp_line
			(start 0.8636 -0.4572)
			(end 0.8636 -0.4064)
			(stroke
				(width 0.1)
				(type default)
			)
			(layer "F.Fab")
		)
		(fp_line
			(start -0.8636 -0.4572)
			(end 0.8636 -0.4572)
			(stroke
				(width 0.1)
				(type default)
			)
			(layer "F.Fab")
		)
		(fp_line
			(start 1.1938 -0.4064)
			(end 1.1938 0.4064)
			(stroke
				(width 0.1)
				(type default)
			)
			(layer "F.Fab")
		)
		(fp_line
			(start 0.8636 -0.4064)
			(end 1.1938 -0.4064)
			(stroke
				(width 0.1)
				(type default)
			)
			(layer "F.Fab")
		)
		(fp_line
			(start -0.8636 -0.4064)
			(end -0.8636 -0.4572)
			(stroke
				(width 0.1)
				(type default)
			)
			(layer "F.Fab")
		)
		(fp_line
			(start -1.1938 -0.4064)
			(end -0.8636 -0.4064)
			(stroke
				(width 0.1)
				(type default)
			)
			(layer "F.Fab")
		)
		(fp_line
			(start 1.1938 0.4064)
			(end 0.8636 0.4064)
			(stroke
				(width 0.1)
				(type default)
			)
			(layer "F.Fab")
		)
		(fp_line
			(start 0.8636 0.4064)
			(end 0.8636 0.4572)
			(stroke
				(width 0.1)
				(type default)
			)
			(layer "F.Fab")
		)
		(fp_line
			(start -0.8636 0.4064)
			(end -1.1938 0.4064)
			(stroke
				(width 0.1)
				(type default)
			)
			(layer "F.Fab")
		)
		(fp_line
			(start -1.1938 0.4064)
			(end -1.1938 -0.4064)
			(stroke
				(width 0.1)
				(type default)
			)
			(layer "F.Fab")
		)
		(fp_line
			(start 0.8636 0.4572)
			(end -0.8636 0.4572)
			(stroke
				(width 0.1)
				(type default)
			)
			(layer "F.Fab")
		)
		(fp_line
			(start -0.8636 0.4572)
			(end -0.8636 0.4064)
			(stroke
				(width 0.1)
				(type default)
			)
			(layer "F.Fab")
		)
		(pad "1" smd rect
			(at -0.7366 0)
			(size 0.7112 0.8128)
			(layers "F.Cu" "F.Mask" "F.Paste")
			(net "P12V_E1S_AVIN_PD_0")
		)
		(pad "2" smd rect
			(at 0.7366 0)
			(size 0.7112 0.8128)
			(layers "F.Cu" "F.Mask" "F.Paste")
			(net "GND")
		)
	)
	(footprint ""
		(layer "F.Cu")
		(at 249.899932 -290.89985)
		(property "Reference" "H12"
			(at 3.83413 0.127254 0)
			(unlocked yes)
			(layer "F.SilkS")
			(effects
				(font
					(size 0.7874 0.5842)
					(thickness 0.1524)
				)
				(justify left)
			)
		)
		(property "Value" ""
			(at 0 0 0)
			(layer "F.Fab")
			(effects
				(font
					(size 1.27 1.27)
				)
			)
		)
		(duplicate_pad_numbers_are_jumpers no)
		(pad "1" thru_hole circle
			(at 0 0)
			(size 6.1976 6.1976)
			(drill 3.7338)
			(layers "*.Cu" "*.Mask")
			(remove_unused_layers no)
			(net "GND")
			(clearance -0.9779)
			(padstack
				(mode front_inner_back)
				(layer "Inner"
					(shape circle)
					(size 5.5372 5.5372)
					(clearance -0.6477)
				)
				(layer "B.Cu"
					(shape circle)
					(size 6.1976 6.1976)
					(clearance -0.9779)
				)
			)
		)
	)
	(footprint ""
		(layer "F.Cu")
		(at 41.492932 -343.716864 180)
		(property "Reference" "PC175"
			(at 0 0 180)
			(layer "F.SilkS")
			(hide yes)
			(effects
				(font
					(size 1.27 1.27)
				)
			)
		)
		(property "Value" ""
			(at 0 0 180)
			(layer "F.Fab")
			(effects
				(font
					(size 1.27 1.27)
				)
			)
		)
		(duplicate_pad_numbers_are_jumpers no)
		(fp_line
			(start 0.7874 0.4064)
			(end -0.7874 0.4064)
			(stroke
				(width 0.1524)
				(type default)
			)
			(layer "F.SilkS")
		)
		(fp_line
			(start 0.7874 -0.4064)
			(end 0.7874 0.4064)
			(stroke
				(width 0.1524)
				(type default)
			)
			(layer "F.SilkS")
		)
		(fp_line
			(start -0.7874 0.4064)
			(end -0.7874 -0.4064)
			(stroke
				(width 0.1524)
				(type default)
			)
			(layer "F.SilkS")
		)
		(fp_line
			(start -0.7874 -0.4064)
			(end 0.7874 -0.4064)
			(stroke
				(width 0.1524)
				(type default)
			)
			(layer "F.SilkS")
		)
		(fp_line
			(start 0.67945 0.3048)
			(end 0.120396 0.3048)
			(stroke
				(width 0.1)
				(type default)
			)
			(layer "F.Fab")
		)
		(fp_line
			(start 0.67945 -0.3048)
			(end 0.67945 0.3048)
			(stroke
				(width 0.1)
				(type default)
			)
			(layer "F.Fab")
		)
		(fp_line
			(start 0.12065 -0.2794)
			(end 0.12065 -0.3048)
			(stroke
				(width 0.1)
				(type default)
			)
			(layer "F.Fab")
		)
		(fp_line
			(start 0.12065 -0.3048)
			(end 0.67945 -0.3048)
			(stroke
				(width 0.1)
				(type default)
			)
			(layer "F.Fab")
		)
		(fp_line
			(start 0.120396 0.3048)
			(end 0.120396 0.2794)
			(stroke
				(width 0.1)
				(type default)
			)
			(layer "F.Fab")
		)
		(fp_line
			(start 0.120396 0.2794)
			(end -0.12065 0.2794)
			(stroke
				(width 0.1)
				(type default)
			)
			(layer "F.Fab")
		)
		(fp_line
			(start -0.12065 0.3048)
			(end -0.67945 0.3048)
			(stroke
				(width 0.1)
				(type default)
			)
			(layer "F.Fab")
		)
		(fp_line
			(start -0.12065 0.2794)
			(end -0.12065 0.3048)
			(stroke
				(width 0.1)
				(type default)
			)
			(layer "F.Fab")
		)
		(fp_line
			(start -0.12065 -0.2794)
			(end 0.12065 -0.2794)
			(stroke
				(width 0.1)
				(type default)
			)
			(layer "F.Fab")
		)
		(fp_line
			(start -0.12065 -0.305054)
			(end -0.12065 -0.2794)
			(stroke
				(width 0.1)
				(type default)
			)
			(layer "F.Fab")
		)
		(fp_line
			(start -0.67945 0.3048)
			(end -0.67945 -0.305054)
			(stroke
				(width 0.1)
				(type default)
			)
			(layer "F.Fab")
		)
		(fp_line
			(start -0.67945 -0.305054)
			(end -0.12065 -0.305054)
			(stroke
				(width 0.1)
				(type default)
			)
			(layer "F.Fab")
		)
		(pad "1" smd circle
			(at -0.40005 0 180)
			(size 0 0)
			(layers "F.Cu" "F.Mask" "F.Paste")
			(net "SW_PVDDIO_P1_SW2")
		)
		(pad "2" smd circle
			(at 0.40005 0 180)
			(size 0 0)
			(layers "F.Cu" "F.Mask" "F.Paste")
			(net "SW_PVDDIO_P1_SW2_RC")
		)
	)
	(footprint ""
		(layer "F.Cu")
		(at 297.554142 -398.2212 180)
		(property "Reference" "R963"
			(at 0 0 180)
			(layer "F.SilkS")
			(hide yes)
			(effects
				(font
					(size 1.27 1.27)
				)
			)
		)
		(property "Value" ""
			(at 0 0 180)
			(layer "F.Fab")
			(effects
				(font
					(size 1.27 1.27)
				)
			)
		)
		(duplicate_pad_numbers_are_jumpers no)
		(fp_line
			(start 0.32512 0.175006)
			(end -0.32512 0.175006)
			(stroke
				(width 0.1)
				(type default)
			)
			(layer "F.Fab")
		)
		(fp_line
			(start 0.32512 -0.175006)
			(end 0.32512 0.175006)
			(stroke
				(width 0.1)
				(type default)
			)
			(layer "F.Fab")
		)
		(fp_line
			(start -0.32512 0.175006)
			(end -0.32512 -0.175006)
			(stroke
				(width 0.1)
				(type default)
			)
			(layer "F.Fab")
		)
		(fp_line
			(start -0.32512 -0.175006)
			(end 0.32512 -0.175006)
			(stroke
				(width 0.1)
				(type default)
			)
			(layer "F.Fab")
		)
		(pad "1" smd rect
			(at -0.2667 0 180)
			(size 0.3048 0.381)
			(layers "F.Cu" "F.Mask" "F.Paste")
			(net "RST_RT_CPU0_P0_RESET_N")
		)
		(pad "2" smd rect
			(at 0.2667 0)
			(size 0.3048 0.381)
			(layers "F.Cu" "F.Mask" "F.Paste")
			(net "RST_RT_CPU0_P0_RESET_R_N")
		)
	)
	(footprint ""
		(layer "F.Cu")
		(at 46.972728 -351.372932 -90)
		(property "Reference" "PC445"
			(at 0 0 270)
			(layer "F.SilkS")
			(hide yes)
			(effects
				(font
					(size 1.27 1.27)
				)
			)
		)
		(property "Value" ""
			(at 0 0 270)
			(layer "F.Fab")
			(effects
				(font
					(size 1.27 1.27)
				)
			)
		)
		(duplicate_pad_numbers_are_jumpers no)
		(fp_line
			(start -0.7874 0.4064)
			(end -0.7874 -0.4064)
			(stroke
				(width 0.1524)
				(type default)
			)
			(layer "F.SilkS")
		)
		(fp_line
			(start 0.7874 0.4064)
			(end -0.7874 0.4064)
			(stroke
				(width 0.1524)
				(type default)
			)
			(layer "F.SilkS")
		)
		(fp_line
			(start -0.7874 -0.4064)
			(end 0.7874 -0.4064)
			(stroke
				(width 0.1524)
				(type default)
			)
			(layer "F.SilkS")
		)
		(fp_line
			(start 0.7874 -0.4064)
			(end 0.7874 0.4064)
			(stroke
				(width 0.1524)
				(type default)
			)
			(layer "F.SilkS")
		)
		(fp_line
			(start -0.67945 0.3048)
			(end -0.67945 -0.305054)
			(stroke
				(width 0.1)
				(type default)
			)
			(layer "F.Fab")
		)
		(fp_line
			(start -0.12065 0.3048)
			(end -0.67945 0.3048)
			(stroke
				(width 0.1)
				(type default)
			)
			(layer "F.Fab")
		)
		(fp_line
			(start 0.120396 0.3048)
			(end 0.120396 0.2794)
			(stroke
				(width 0.1)
				(type default)
			)
			(layer "F.Fab")
		)
		(fp_line
			(start 0.67945 0.3048)
			(end 0.120396 0.3048)
			(stroke
				(width 0.1)
				(type default)
			)
			(layer "F.Fab")
		)
		(fp_line
			(start -0.12065 0.2794)
			(end -0.12065 0.3048)
			(stroke
				(width 0.1)
				(type default)
			)
			(layer "F.Fab")
		)
		(fp_line
			(start 0.120396 0.2794)
			(end -0.12065 0.2794)
			(stroke
				(width 0.1)
				(type default)
			)
			(layer "F.Fab")
		)
		(fp_line
			(start -0.12065 -0.2794)
			(end 0.12065 -0.2794)
			(stroke
				(width 0.1)
				(type default)
			)
			(layer "F.Fab")
		)
		(fp_line
			(start 0.12065 -0.2794)
			(end 0.12065 -0.3048)
			(stroke
				(width 0.1)
				(type default)
			)
			(layer "F.Fab")
		)
		(fp_line
			(start 0.12065 -0.3048)
			(end 0.67945 -0.3048)
			(stroke
				(width 0.1)
				(type default)
			)
			(layer "F.Fab")
		)
		(fp_line
			(start 0.67945 -0.3048)
			(end 0.67945 0.3048)
			(stroke
				(width 0.1)
				(type default)
			)
			(layer "F.Fab")
		)
		(fp_line
			(start -0.67945 -0.305054)
			(end -0.12065 -0.305054)
			(stroke
				(width 0.1)
				(type default)
			)
			(layer "F.Fab")
		)
		(fp_line
			(start -0.12065 -0.305054)
			(end -0.12065 -0.2794)
			(stroke
				(width 0.1)
				(type default)
			)
			(layer "F.Fab")
		)
		(pad "1" smd circle
			(at -0.40005 0 270)
			(size 0 0)
			(layers "F.Cu" "F.Mask" "F.Paste")
			(net "SW_PVDDIO_P1_BOOT2_R")
		)
		(pad "2" smd circle
			(at 0.40005 0 270)
			(size 0 0)
			(layers "F.Cu" "F.Mask" "F.Paste")
			(net "SW_PVDDIO_P1_BOOTR2")
		)
	)
)
